# T6G (Grand Teton) — schematic netlist excerpt (pin names and nets, part order shuffled) for the footprints in the layout excerpt that follows; sources: Cadence DE-HDL packaged netlist, KiCad conversion of 04192023_DAF0TMB3IC0_F0TG_MB_C_brd_V02_OCP.brd

C6739  Q_CAP_DIFFBUS  DIFF BUS_0.22UF 6.3V 20% X6S  pkg C0201  page 352 : \1\ = P5E_CPU1_P3_TX_BUF_C_DP<7> ; \2\ = P5E_CPU1_P3_TX_BUF_DP<7>
R305  Q_RES  1K 1% CHIP  pkg 0402LF  page 100 : A = PWRGD_CHC_CPU1_DIMM ; B = PWRGD_CHAF_CPU1
R6006  Q_RES  0 5% CHIP  pkg 0402LF  page 150 : A = I3C_SCM_3_SCL ; B = I3C_SCM_3_R_SCL

(kicad_pcb
	(version 20260206)
	(generator "pcbnew")
	(generator_version "10.0")
	(general
		(thickness 1.6)
		(legacy_teardrops no)
	)
	(paper "A4")
	(title_block
		(title "04192023_DAF0TMB3IC0_F0TG_MB_C_brd_V02_OCP.brd")
		(comment 1 "Grand Teton / footprints 5828-5830 of 8354")
	)
	(layers
		(0 "F.Cu" signal "TOP")
		(4 "In1.Cu" signal "GND")
		(6 "In2.Cu" signal "IN1")
		(8 "In3.Cu" signal "GND1")
		(10 "In4.Cu" signal "IN2")
		(12 "In5.Cu" signal "GND2")
		(14 "In6.Cu" signal "IN3")
		(16 "In7.Cu" signal "GND3")
		(18 "In8.Cu" signal "VCC")
		(20 "In9.Cu" signal "VCC1")
		(22 "In10.Cu" signal "GND4")
		(24 "In11.Cu" signal "IN4")
		(26 "In12.Cu" signal "GND5")
		(28 "In13.Cu" signal "IN5")
		(30 "In14.Cu" signal "GND6")
		(32 "In15.Cu" signal "IN6")
		(34 "In16.Cu" signal "GND7")
		(2 "B.Cu" signal "BOTTOM")
		(9 "F.Adhes" user "F.Adhesive")
		(11 "B.Adhes" user "B.Adhesive")
		(13 "F.Paste" user "Package Geometry/Pastemask Top")
		(15 "B.Paste" user "Package Geometry/Pastemask Bottom")
		(5 "F.SilkS" user "Ref Des/Silkscreen Top")
		(7 "B.SilkS" user "Ref Des/Silkscreen Bottom")
		(1 "F.Mask" user "Board Geometry/Soldermask Top")
		(3 "B.Mask" user "Board Geometry/Soldermask Bottom")
		(17 "Dwgs.User" user "User.Drawings")
		(19 "Cmts.User" user "User.Comments")
		(21 "Eco1.User" user "User.Eco1")
		(23 "Eco2.User" user "User.Eco2")
		(25 "Edge.Cuts" user "Board Geometry/Outline")
		(27 "Margin" user)
		(31 "F.CrtYd" user "Package Geometry/Place Bound Top")
		(29 "B.CrtYd" user "Package Geometry/Place Bound Bottom")
		(35 "F.Fab" user "Ref Des/Assembly Top")
		(33 "B.Fab" user "Ref Des/Assembly Bottom")
	)
	(footprint ""
		(layer "B.Cu")
		(at 40.045386 -190.948564 180)
		(property "Reference" "R305"
			(at 0 0 0)
			(layer "B.SilkS")
			(hide yes)
			(effects
				(font
					(size 1.27 1.27)
				)
				(justify mirror)
			)
		)
		(property "Value" ""
			(at 0 0 0)
			(layer "B.Fab")
			(effects
				(font
					(size 1.27 1.27)
				)
				(justify mirror)
			)
		)
		(duplicate_pad_numbers_are_jumpers no)
		(fp_line
			(start 0.7874 0.4064)
			(end 0.7874 -0.4064)
			(stroke
				(width 0.1524)
				(type default)
			)
			(layer "B.SilkS")
		)
		(fp_line
			(start 0.7874 -0.4064)
			(end -0.7874 -0.4064)
			(stroke
				(width 0.1524)
				(type default)
			)
			(layer "B.SilkS")
		)
		(fp_line
			(start -0.7874 0.4064)
			(end 0.7874 0.4064)
			(stroke
				(width 0.1524)
				(type default)
			)
			(layer "B.SilkS")
		)
		(fp_line
			(start -0.7874 -0.4064)
			(end -0.7874 0.4064)
			(stroke
				(width 0.1524)
				(type default)
			)
			(layer "B.SilkS")
		)
		(fp_line
			(start 0.67945 0.3048)
			(end 0.67945 -0.305054)
			(stroke
				(width 0.1)
				(type default)
			)
			(layer "B.Fab")
		)
		(fp_line
			(start 0.67945 -0.305054)
			(end 0.12065 -0.305054)
			(stroke
				(width 0.1)
				(type default)
			)
			(layer "B.Fab")
		)
		(fp_line
			(start 0.12065 0.3048)
			(end 0.67945 0.3048)
			(stroke
				(width 0.1)
				(type default)
			)
			(layer "B.Fab")
		)
		(fp_line
			(start 0.12065 0.2794)
			(end 0.12065 0.3048)
			(stroke
				(width 0.1)
				(type default)
			)
			(layer "B.Fab")
		)
		(fp_line
			(start 0.12065 -0.2794)
			(end -0.12065 -0.2794)
			(stroke
				(width 0.1)
				(type default)
			)
			(layer "B.Fab")
		)
		(fp_line
			(start 0.12065 -0.305054)
			(end 0.12065 -0.2794)
			(stroke
				(width 0.1)
				(type default)
			)
			(layer "B.Fab")
		)
		(fp_line
			(start -0.120396 0.3048)
			(end -0.120396 0.2794)
			(stroke
				(width 0.1)
				(type default)
			)
			(layer "B.Fab")
		)
		(fp_line
			(start -0.120396 0.2794)
			(end 0.12065 0.2794)
			(stroke
				(width 0.1)
				(type default)
			)
			(layer "B.Fab")
		)
		(fp_line
			(start -0.12065 -0.2794)
			(end -0.12065 -0.3048)
			(stroke
				(width 0.1)
				(type default)
			)
			(layer "B.Fab")
		)
		(fp_line
			(start -0.12065 -0.3048)
			(end -0.67945 -0.3048)
			(stroke
				(width 0.1)
				(type default)
			)
			(layer "B.Fab")
		)
		(fp_line
			(start -0.67945 0.3048)
			(end -0.120396 0.3048)
			(stroke
				(width 0.1)
				(type default)
			)
			(layer "B.Fab")
		)
		(fp_line
			(start -0.67945 -0.3048)
			(end -0.67945 0.3048)
			(stroke
				(width 0.1)
				(type default)
			)
			(layer "B.Fab")
		)
		(pad "1" smd circle
			(at 0.40005 0)
			(size 0 0)
			(layers "B.Cu" "B.Mask" "B.Paste")
			(net "PWRGD_CHC_CPU1_DIMM")
		)
		(pad "2" smd circle
			(at -0.40005 0)
			(size 0 0)
			(layers "B.Cu" "B.Mask" "B.Paste")
			(net "PWRGD_CHAF_CPU1")
		)
	)
	(footprint ""
		(layer "B.Cu")
		(at 184.05983 -13.60043 -90)
		(property "Reference" "R6006"
			(at 0 0 90)
			(layer "B.SilkS")
			(hide yes)
			(effects
				(font
					(size 1.27 1.27)
				)
				(justify mirror)
			)
		)
		(property "Value" ""
			(at 0 0 90)
			(layer "B.Fab")
			(effects
				(font
					(size 1.27 1.27)
				)
				(justify mirror)
			)
		)
		(duplicate_pad_numbers_are_jumpers no)
		(fp_line
			(start -0.7874 0.4064)
			(end 0.7874 0.4064)
			(stroke
				(width 0.1524)
				(type default)
			)
			(layer "B.SilkS")
		)
		(fp_line
			(start 0.7874 0.4064)
			(end 0.7874 -0.4064)
			(stroke
				(width 0.1524)
				(type default)
			)
			(layer "B.SilkS")
		)
		(fp_line
			(start -0.7874 -0.4064)
			(end -0.7874 0.4064)
			(stroke
				(width 0.1524)
				(type default)
			)
			(layer "B.SilkS")
		)
		(fp_line
			(start 0.7874 -0.4064)
			(end -0.7874 -0.4064)
			(stroke
				(width 0.1524)
				(type default)
			)
			(layer "B.SilkS")
		)
		(fp_line
			(start -0.67945 0.3048)
			(end -0.120396 0.3048)
			(stroke
				(width 0.1)
				(type default)
			)
			(layer "B.Fab")
		)
		(fp_line
			(start -0.120396 0.3048)
			(end -0.120396 0.2794)
			(stroke
				(width 0.1)
				(type default)
			)
			(layer "B.Fab")
		)
		(fp_line
			(start 0.12065 0.3048)
			(end 0.67945 0.3048)
			(stroke
				(width 0.1)
				(type default)
			)
			(layer "B.Fab")
		)
		(fp_line
			(start 0.67945 0.3048)
			(end 0.67945 -0.305054)
			(stroke
				(width 0.1)
				(type default)
			)
			(layer "B.Fab")
		)
		(fp_line
			(start -0.120396 0.2794)
			(end 0.12065 0.2794)
			(stroke
				(width 0.1)
				(type default)
			)
			(layer "B.Fab")
		)
		(fp_line
			(start 0.12065 0.2794)
			(end 0.12065 0.3048)
			(stroke
				(width 0.1)
				(type default)
			)
			(layer "B.Fab")
		)
		(fp_line
			(start -0.12065 -0.2794)
			(end -0.12065 -0.3048)
			(stroke
				(width 0.1)
				(type default)
			)
			(layer "B.Fab")
		)
		(fp_line
			(start 0.12065 -0.2794)
			(end -0.12065 -0.2794)
			(stroke
				(width 0.1)
				(type default)
			)
			(layer "B.Fab")
		)
		(fp_line
			(start -0.67945 -0.3048)
			(end -0.67945 0.3048)
			(stroke
				(width 0.1)
				(type default)
			)
			(layer "B.Fab")
		)
		(fp_line
			(start -0.12065 -0.3048)
			(end -0.67945 -0.3048)
			(stroke
				(width 0.1)
				(type default)
			)
			(layer "B.Fab")
		)
		(fp_line
			(start 0.12065 -0.305054)
			(end 0.12065 -0.2794)
			(stroke
				(width 0.1)
				(type default)
			)
			(layer "B.Fab")
		)
		(fp_line
			(start 0.67945 -0.305054)
			(end 0.12065 -0.305054)
			(stroke
				(width 0.1)
				(type default)
			)
			(layer "B.Fab")
		)
		(pad "1" smd circle
			(at 0.40005 0 90)
			(size 0 0)
			(layers "B.Cu" "B.Mask" "B.Paste")
			(net "I3C_SCM_3_SCL")
		)
		(pad "2" smd circle
			(at -0.40005 0 90)
			(size 0 0)
			(layers "B.Cu" "B.Mask" "B.Paste")
			(net "I3C_SCM_3_R_SCL")
		)
	)
	(footprint ""
		(layer "B.Cu")
		(at 138.757406 -408.517344 90)
		(property "Reference" "C6739"
			(at 0 0 90)
			(layer "B.SilkS")
			(hide yes)
			(effects
				(font
					(size 1.27 1.27)
				)
				(justify mirror)
			)
		)
		(property "Value" ""
			(at 0 0 90)
			(layer "B.Fab")
			(effects
				(font
					(size 1.27 1.27)
				)
				(justify mirror)
			)
		)
		(duplicate_pad_numbers_are_jumpers no)
		(fp_line
			(start 0.299974 -0.150114)
			(end -0.299974 -0.150114)
			(stroke
				(width 0.1)
				(type default)
			)
			(layer "B.Fab")
		)
		(fp_line
			(start -0.299974 -0.150114)
			(end -0.299974 0.150114)
			(stroke
				(width 0.1)
				(type default)
			)
			(layer "B.Fab")
		)
		(fp_line
			(start 0.299974 0.150114)
			(end 0.299974 -0.150114)
			(stroke
				(width 0.1)
				(type default)
			)
			(layer "B.Fab")
		)
		(fp_line
			(start -0.299974 0.150114)
			(end 0.299974 0.150114)
			(stroke
				(width 0.1)
				(type default)
			)
			(layer "B.Fab")
		)
		(pad "1" smd rect
			(at 0.2667 0 270)
			(size 0.3048 0.381)
			(layers "B.Cu" "B.Mask" "B.Paste")
			(net "P5E_CPU1_P3_TX_BUF_C_DP<7>")
		)
		(pad "2" smd rect
			(at -0.2667 0 270)
			(size 0.3048 0.381)
			(layers "B.Cu" "B.Mask" "B.Paste")
			(net "P5E_CPU1_P3_TX_BUF_DP<7>")
		)
	)
)
